# SCM (Grand Teton) — schematic netlist excerpt (pin names and nets, part order shuffled) for the footprints in the layout excerpt that follows; sources: Cadence DE-HDL packaged netlist, KiCad conversion of 12092022_DA0F0TMDCD0_F0T_Management_Board_D_brd_V3_OCP.brd

C300  Q_CAP  0.1UF 25V 10% X7R  pkg 0402  page 28 : A = P3V3_AUX ; B = GND
C160  Q_CAP  0.1UF 25V 10% X7R  pkg 0402  page 41 : A = VCCIO5 ; B = GND

(kicad_pcb
	(version 20260206)
	(generator "pcbnew")
	(generator_version "10.0")
	(general
		(thickness 1.6)
		(legacy_teardrops no)
	)
	(paper "A4")
	(title_block
		(title "12092022_DA0F0TMDCD0_F0T_Management_Board_D_brd_V3_OCP.brd")
		(comment 1 "Grand Teton / footprints 1386-1387 of 1440")
	)
	(layers
		(0 "F.Cu" signal "TOP")
		(4 "In1.Cu" signal "GND")
		(6 "In2.Cu" signal "IN1")
		(8 "In3.Cu" signal "GND1")
		(10 "In4.Cu" signal "IN2")
		(12 "In5.Cu" signal "VCC")
		(14 "In6.Cu" signal "VCC1")
		(16 "In7.Cu" signal "IN3")
		(18 "In8.Cu" signal "GND2")
		(20 "In9.Cu" signal "IN4")
		(22 "In10.Cu" signal "GND3")
		(2 "B.Cu" signal "BOTTOM")
		(9 "F.Adhes" user "F.Adhesive")
		(11 "B.Adhes" user "B.Adhesive")
		(13 "F.Paste" user "Package Geometry/Pastemask Top")
		(15 "B.Paste" user "Package Geometry/Pastemask Bottom")
		(5 "F.SilkS" user "Ref Des/Silkscreen Top")
		(7 "B.SilkS" user "Ref Des/Silkscreen Bottom")
		(1 "F.Mask" user "Board Geometry/Soldermask Top")
		(3 "B.Mask" user "Board Geometry/Soldermask Bottom")
		(17 "Dwgs.User" user "User.Drawings")
		(19 "Cmts.User" user "User.Comments")
		(21 "Eco1.User" user "User.Eco1")
		(23 "Eco2.User" user "User.Eco2")
		(25 "Edge.Cuts" user "Board Geometry/Outline")
		(27 "Margin" user)
		(31 "F.CrtYd" user "Package Geometry/Place Bound Top")
		(29 "B.CrtYd" user "Package Geometry/Place Bound Bottom")
		(35 "F.Fab" user "Ref Des/Assembly Top")
		(33 "B.Fab" user "Ref Des/Assembly Bottom")
	)
	(footprint ""
		(layer "B.Cu")
		(at 55.486808 -94.520766 180)
		(property "Reference" "C300"
			(at 0 0 0)
			(layer "B.SilkS")
			(hide yes)
			(effects
				(font
					(size 1.27 1.27)
				)
				(justify mirror)
			)
		)
		(property "Value" ""
			(at 0 0 0)
			(layer "B.Fab")
			(effects
				(font
					(size 1.27 1.27)
				)
				(justify mirror)
			)
		)
		(duplicate_pad_numbers_are_jumpers no)
		(fp_line
			(start 0.7874 0.4064)
			(end 0.7874 -0.4064)
			(stroke
				(width 0.1524)
				(type default)
			)
			(layer "B.SilkS")
		)
		(fp_line
			(start 0.7874 -0.4064)
			(end -0.7874 -0.4064)
			(stroke
				(width 0.1524)
				(type default)
			)
			(layer "B.SilkS")
		)
		(fp_line
			(start -0.7874 0.4064)
			(end 0.7874 0.4064)
			(stroke
				(width 0.1524)
				(type default)
			)
			(layer "B.SilkS")
		)
		(fp_line
			(start -0.7874 -0.4064)
			(end -0.7874 0.4064)
			(stroke
				(width 0.1524)
				(type default)
			)
			(layer "B.SilkS")
		)
		(fp_line
			(start 0.67945 0.3048)
			(end 0.67945 -0.305054)
			(stroke
				(width 0.1)
				(type default)
			)
			(layer "B.Fab")
		)
		(fp_line
			(start 0.67945 -0.305054)
			(end 0.12065 -0.305054)
			(stroke
				(width 0.1)
				(type default)
			)
			(layer "B.Fab")
		)
		(fp_line
			(start 0.12065 0.3048)
			(end 0.67945 0.3048)
			(stroke
				(width 0.1)
				(type default)
			)
			(layer "B.Fab")
		)
		(fp_line
			(start 0.12065 0.2794)
			(end 0.12065 0.3048)
			(stroke
				(width 0.1)
				(type default)
			)
			(layer "B.Fab")
		)
		(fp_line
			(start 0.12065 -0.2794)
			(end -0.12065 -0.2794)
			(stroke
				(width 0.1)
				(type default)
			)
			(layer "B.Fab")
		)
		(fp_line
			(start 0.12065 -0.305054)
			(end 0.12065 -0.2794)
			(stroke
				(width 0.1)
				(type default)
			)
			(layer "B.Fab")
		)
		(fp_line
			(start -0.120396 0.3048)
			(end -0.120396 0.2794)
			(stroke
				(width 0.1)
				(type default)
			)
			(layer "B.Fab")
		)
		(fp_line
			(start -0.120396 0.2794)
			(end 0.12065 0.2794)
			(stroke
				(width 0.1)
				(type default)
			)
			(layer "B.Fab")
		)
		(fp_line
			(start -0.12065 -0.2794)
			(end -0.12065 -0.3048)
			(stroke
				(width 0.1)
				(type default)
			)
			(layer "B.Fab")
		)
		(fp_line
			(start -0.12065 -0.3048)
			(end -0.67945 -0.3048)
			(stroke
				(width 0.1)
				(type default)
			)
			(layer "B.Fab")
		)
		(fp_line
			(start -0.67945 0.3048)
			(end -0.120396 0.3048)
			(stroke
				(width 0.1)
				(type default)
			)
			(layer "B.Fab")
		)
		(fp_line
			(start -0.67945 -0.3048)
			(end -0.67945 0.3048)
			(stroke
				(width 0.1)
				(type default)
			)
			(layer "B.Fab")
		)
		(pad "1" smd circle
			(at 0.40005 0)
			(size 0 0)
			(layers "B.Cu" "B.Mask" "B.Paste")
			(net "P3V3_AUX")
		)
		(pad "2" smd circle
			(at -0.40005 0)
			(size 0 0)
			(layers "B.Cu" "B.Mask" "B.Paste")
			(net "GND")
		)
	)
	(footprint ""
		(layer "B.Cu")
		(at 26.67 -90.805 180)
		(property "Reference" "C160"
			(at 0 0 0)
			(layer "B.SilkS")
			(hide yes)
			(effects
				(font
					(size 1.27 1.27)
				)
				(justify mirror)
			)
		)
		(property "Value" ""
			(at 0 0 0)
			(layer "B.Fab")
			(effects
				(font
					(size 1.27 1.27)
				)
				(justify mirror)
			)
		)
		(duplicate_pad_numbers_are_jumpers no)
		(fp_line
			(start 0.69215 0.2921)
			(end 0.69215 -0.2921)
			(stroke
				(width 0.1524)
				(type default)
			)
			(layer "B.SilkS")
		)
		(fp_line
			(start 0.69215 -0.2921)
			(end -0.69215 -0.2921)
			(stroke
				(width 0.1524)
				(type default)
			)
			(layer "B.SilkS")
		)
		(fp_line
			(start -0.69215 0.2921)
			(end 0.69215 0.2921)
			(stroke
				(width 0.1524)
				(type default)
			)
			(layer "B.SilkS")
		)
		(fp_line
			(start -0.69215 -0.2921)
			(end -0.69215 0.2921)
			(stroke
				(width 0.1524)
				(type default)
			)
			(layer "B.SilkS")
		)
		(fp_line
			(start 0.51435 0.2794)
			(end 0.51435 -0.2794)
			(stroke
				(width 0.1)
				(type default)
			)
			(layer "B.Fab")
		)
		(fp_line
			(start 0.51435 -0.2794)
			(end -0.51435 -0.2794)
			(stroke
				(width 0.1)
				(type default)
			)
			(layer "B.Fab")
		)
		(fp_line
			(start -0.51435 0.2794)
			(end 0.51435 0.2794)
			(stroke
				(width 0.1)
				(type default)
			)
			(layer "B.Fab")
		)
		(fp_line
			(start -0.51435 -0.2794)
			(end -0.51435 0.2794)
			(stroke
				(width 0.1)
				(type default)
			)
			(layer "B.Fab")
		)
		(pad "1" smd circle
			(at 0.40005 0)
			(size 0 0)
			(layers "B.Cu" "B.Mask" "B.Paste")
			(net "VCCIO5")
		)
		(pad "2" smd circle
			(at -0.40005 0)
			(size 0 0)
			(layers "B.Cu" "B.Mask" "B.Paste")
			(net "GND")
		)
		(zone
			(layer "B.Cu")
			(hatch none 0.5)
			(connect_pads
				(clearance 0)
			)
			(min_thickness 0.25)
			(keepout
				(tracks not_allowed)
				(vias allowed)
				(pads allowed)
				(copperpour not_allowed)
				(footprints allowed)
			)
			(placement
				(enabled no)
				(sheetname "")
			)
			(fill
				(thermal_gap 0.5)
				(thermal_bridge_width 0.5)
				(island_removal_mode 0)
			)
			(polygon
				(pts
					(xy 26.4795 -90.89263) (xy 26.57094 -90.950796) (xy 26.77033 -90.950796) (xy 26.8605 -90.89263)
					(xy 26.8605 -90.71737) (xy 26.77033 -90.65895) (xy 26.57094 -90.65895) (xy 26.4795 -90.717116)
				)
			)
		)
	)
)
